# S9S_MB_2U (Grand Teton) — schematic netlist excerpt (pin names and nets, part order shuffled) for the footprints in the layout excerpt that follows; sources: Cadence DE-HDL packaged netlist, KiCad conversion of 03242023_DA0F0TMBIJ0_F0T_Motherboard_J_brd_V01_OCP.brd

PC529_P1_4  Q_CAP  1UF 16V 10% X6S  pkg C0402  page 286 : A = SW_P12V_PVCCIN_CPU1_FLT ; B = GND
PC1669  Q_CAP  22UF 16V 20% X6S  pkg C0805  page 271 : A = SW_P12V_PVCCFA_EHV_FIVRA_CPU0_L ; B = GND
C1792  Q_CAP_DIFFBUS  DIFF BUS_0.22UF 6.3V 20% X6S  pkg C0201  page 175 : \1\ = P5E_CPU0_PE4_TX_C_DP<14> ; \2\ = P5E_CPU0_PE4_TX_DP<14>

(kicad_pcb
	(version 20260206)
	(generator "pcbnew")
	(generator_version "10.0")
	(general
		(thickness 1.6)
		(legacy_teardrops no)
	)
	(paper "A4")
	(title_block
		(title "03242023_DA0F0TMBIJ0_F0T_Motherboard_J_brd_V01_OCP.brd")
		(comment 1 "Grand Teton / footprints 1527-1529 of 6105")
	)
	(layers
		(0 "F.Cu" signal "TOP")
		(4 "In1.Cu" signal "GND")
		(6 "In2.Cu" signal "IN1")
		(8 "In3.Cu" signal "GND1")
		(10 "In4.Cu" signal "IN2")
		(12 "In5.Cu" signal "GND2")
		(14 "In6.Cu" signal "IN3")
		(16 "In7.Cu" signal "GND3")
		(18 "In8.Cu" signal "VCC")
		(20 "In9.Cu" signal "VCC1")
		(22 "In10.Cu" signal "GND4")
		(24 "In11.Cu" signal "IN4")
		(26 "In12.Cu" signal "GND5")
		(28 "In13.Cu" signal "IN5")
		(30 "In14.Cu" signal "GND6")
		(32 "In15.Cu" signal "IN6")
		(34 "In16.Cu" signal "GND7")
		(2 "B.Cu" signal "BOTTOM")
		(9 "F.Adhes" user "F.Adhesive")
		(11 "B.Adhes" user "B.Adhesive")
		(13 "F.Paste" user "Package Geometry/Pastemask Top")
		(15 "B.Paste" user "Package Geometry/Pastemask Bottom")
		(5 "F.SilkS" user "Ref Des/Silkscreen Top")
		(7 "B.SilkS" user "Ref Des/Silkscreen Bottom")
		(1 "F.Mask" user "Board Geometry/Soldermask Top")
		(3 "B.Mask" user "Board Geometry/Soldermask Bottom")
		(17 "Dwgs.User" user "User.Drawings")
		(19 "Cmts.User" user "User.Comments")
		(21 "Eco1.User" user "User.Eco1")
		(23 "Eco2.User" user "User.Eco2")
		(25 "Edge.Cuts" user "Board Geometry/Outline")
		(27 "Margin" user)
		(31 "F.CrtYd" user "Package Geometry/Place Bound Top")
		(29 "B.CrtYd" user "Package Geometry/Place Bound Bottom")
		(35 "F.Fab" user "Ref Des/Assembly Top")
		(33 "B.Fab" user "Ref Des/Assembly Bottom")
	)
	(footprint ""
		(layer "F.Cu")
		(at 125.048518 -333.804514 -90)
		(property "Reference" "PC529_P1_4"
			(at 0 0 270)
			(layer "F.SilkS")
			(hide yes)
			(effects
				(font
					(size 1.27 1.27)
				)
			)
		)
		(property "Value" ""
			(at 0 0 270)
			(layer "F.Fab")
			(effects
				(font
					(size 1.27 1.27)
				)
			)
		)
		(duplicate_pad_numbers_are_jumpers no)
		(fp_line
			(start -0.7874 0.4064)
			(end -0.7874 -0.4064)
			(stroke
				(width 0.1524)
				(type default)
			)
			(layer "F.SilkS")
		)
		(fp_line
			(start 0.7874 0.4064)
			(end -0.7874 0.4064)
			(stroke
				(width 0.1524)
				(type default)
			)
			(layer "F.SilkS")
		)
		(fp_line
			(start -0.7874 -0.4064)
			(end 0.7874 -0.4064)
			(stroke
				(width 0.1524)
				(type default)
			)
			(layer "F.SilkS")
		)
		(fp_line
			(start 0.7874 -0.4064)
			(end 0.7874 0.4064)
			(stroke
				(width 0.1524)
				(type default)
			)
			(layer "F.SilkS")
		)
		(fp_line
			(start -0.67945 0.3048)
			(end -0.67945 -0.305054)
			(stroke
				(width 0.1)
				(type default)
			)
			(layer "F.Fab")
		)
		(fp_line
			(start -0.12065 0.3048)
			(end -0.67945 0.3048)
			(stroke
				(width 0.1)
				(type default)
			)
			(layer "F.Fab")
		)
		(fp_line
			(start 0.120396 0.3048)
			(end 0.120396 0.2794)
			(stroke
				(width 0.1)
				(type default)
			)
			(layer "F.Fab")
		)
		(fp_line
			(start 0.67945 0.3048)
			(end 0.120396 0.3048)
			(stroke
				(width 0.1)
				(type default)
			)
			(layer "F.Fab")
		)
		(fp_line
			(start -0.12065 0.2794)
			(end -0.12065 0.3048)
			(stroke
				(width 0.1)
				(type default)
			)
			(layer "F.Fab")
		)
		(fp_line
			(start 0.120396 0.2794)
			(end -0.12065 0.2794)
			(stroke
				(width 0.1)
				(type default)
			)
			(layer "F.Fab")
		)
		(fp_line
			(start -0.12065 -0.2794)
			(end 0.12065 -0.2794)
			(stroke
				(width 0.1)
				(type default)
			)
			(layer "F.Fab")
		)
		(fp_line
			(start 0.12065 -0.2794)
			(end 0.12065 -0.3048)
			(stroke
				(width 0.1)
				(type default)
			)
			(layer "F.Fab")
		)
		(fp_line
			(start 0.12065 -0.3048)
			(end 0.67945 -0.3048)
			(stroke
				(width 0.1)
				(type default)
			)
			(layer "F.Fab")
		)
		(fp_line
			(start 0.67945 -0.3048)
			(end 0.67945 0.3048)
			(stroke
				(width 0.1)
				(type default)
			)
			(layer "F.Fab")
		)
		(fp_line
			(start -0.67945 -0.305054)
			(end -0.12065 -0.305054)
			(stroke
				(width 0.1)
				(type default)
			)
			(layer "F.Fab")
		)
		(fp_line
			(start -0.12065 -0.305054)
			(end -0.12065 -0.2794)
			(stroke
				(width 0.1)
				(type default)
			)
			(layer "F.Fab")
		)
		(pad "1" smd circle
			(at -0.40005 0 270)
			(size 0 0)
			(layers "F.Cu" "F.Mask" "F.Paste")
			(net "SW_P12V_PVCCIN_CPU1_FLT")
		)
		(pad "2" smd circle
			(at 0.40005 0 270)
			(size 0 0)
			(layers "F.Cu" "F.Mask" "F.Paste")
			(net "GND")
		)
	)
	(footprint ""
		(layer "F.Cu")
		(at 347.754448 -402.371052 -90)
		(property "Reference" "C1792"
			(at 0 0 270)
			(layer "F.SilkS")
			(hide yes)
			(effects
				(font
					(size 1.27 1.27)
				)
			)
		)
		(property "Value" ""
			(at 0 0 270)
			(layer "F.Fab")
			(effects
				(font
					(size 1.27 1.27)
				)
			)
		)
		(duplicate_pad_numbers_are_jumpers no)
		(fp_line
			(start -0.299974 0.150114)
			(end -0.299974 -0.150114)
			(stroke
				(width 0.1)
				(type default)
			)
			(layer "F.Fab")
		)
		(fp_line
			(start 0.299974 0.150114)
			(end -0.299974 0.150114)
			(stroke
				(width 0.1)
				(type default)
			)
			(layer "F.Fab")
		)
		(fp_line
			(start -0.299974 -0.150114)
			(end 0.299974 -0.150114)
			(stroke
				(width 0.1)
				(type default)
			)
			(layer "F.Fab")
		)
		(fp_line
			(start 0.299974 -0.150114)
			(end 0.299974 0.150114)
			(stroke
				(width 0.1)
				(type default)
			)
			(layer "F.Fab")
		)
		(pad "1" smd rect
			(at -0.2667 0 270)
			(size 0.3048 0.381)
			(layers "F.Cu" "F.Mask" "F.Paste")
			(net "P5E_CPU0_PE4_TX_C_DP<14>")
		)
		(pad "2" smd rect
			(at 0.2667 0 270)
			(size 0.3048 0.381)
			(layers "F.Cu" "F.Mask" "F.Paste")
			(net "P5E_CPU0_PE4_TX_DP<14>")
		)
	)
	(footprint ""
		(layer "F.Cu")
		(at 304.058828 -364.929928)
		(property "Reference" "PC1669"
			(at 0 0 0)
			(layer "F.SilkS")
			(hide yes)
			(effects
				(font
					(size 1.27 1.27)
				)
			)
		)
		(property "Value" ""
			(at 0 0 0)
			(layer "F.Fab")
			(effects
				(font
					(size 1.27 1.27)
				)
			)
		)
		(duplicate_pad_numbers_are_jumpers no)
		(fp_line
			(start -1.524 -0.762)
			(end 1.524 -0.762)
			(stroke
				(width 0.1524)
				(type default)
			)
			(layer "F.SilkS")
		)
		(fp_line
			(start -1.524 0.762)
			(end -1.524 -0.762)
			(stroke
				(width 0.1524)
				(type default)
			)
			(layer "F.SilkS")
		)
		(fp_line
			(start 1.524 -0.762)
			(end 1.524 0.762)
			(stroke
				(width 0.1524)
				(type default)
			)
			(layer "F.SilkS")
		)
		(fp_line
			(start 1.524 0.762)
			(end -1.524 0.762)
			(stroke
				(width 0.1524)
				(type default)
			)
			(layer "F.SilkS")
		)
		(fp_line
			(start -1.1049 -0.724916)
			(end -1.1049 0.724916)
			(stroke
				(width 0.1)
				(type default)
			)
			(layer "F.Fab")
		)
		(fp_line
			(start -1.1049 0.724916)
			(end 1.1049 0.724916)
			(stroke
				(width 0.1)
				(type default)
			)
			(layer "F.Fab")
		)
		(fp_line
			(start 1.1049 -0.724916)
			(end -1.1049 -0.724916)
			(stroke
				(width 0.1)
				(type default)
			)
			(layer "F.Fab")
		)
		(fp_line
			(start 1.1049 0.724916)
			(end 1.1049 -0.724916)
			(stroke
				(width 0.1)
				(type default)
			)
			(layer "F.Fab")
		)
		(pad "1" smd rect
			(at -0.889 0 180)
			(size 1.016 1.27)
			(layers "F.Cu" "F.Mask" "F.Paste")
			(net "SW_P12V_PVCCFA_EHV_FIVRA_CPU0_L")
		)
		(pad "2" smd rect
			(at 0.889 0 180)
			(size 1.016 1.27)
			(layers "F.Cu" "F.Mask" "F.Paste")
			(net "GND")
		)
	)
)
